(kicad_pcb
	(version 20221018)
	(generator pcbnew)
	(general
    (thickness 1.562)
  )
	(paper "A4")
	(title_block
    (title "Thunderbolt PCIe Adaper")
    (date "2024-07-09")
    (rev "1.0.3")
    (comment 1 "www.antmicro.com")
    (comment 2 "Antmicro Ltd.")
		(comment 9 "footprints 106-114 of 271")
	)
	(layers
    (0 "F.Cu" signal)
    (1 "In1.Cu" signal)
    (2 "In2.Cu" signal)
    (3 "In3.Cu" signal)
    (4 "In4.Cu" signal)
    (31 "B.Cu" signal)
    (32 "B.Adhes" user "B.Adhesive")
    (33 "F.Adhes" user "F.Adhesive")
    (34 "B.Paste" user)
    (35 "F.Paste" user)
    (36 "B.SilkS" user "B.Silkscreen")
    (37 "F.SilkS" user "F.Silkscreen")
    (38 "B.Mask" user)
    (39 "F.Mask" user)
    (40 "Dwgs.User" user "User.Drawings")
    (41 "Cmts.User" user "User.Comments")
    (42 "Eco1.User" user "User.Eco1")
    (43 "Eco2.User" user "User.Eco2")
    (44 "Edge.Cuts" user)
    (45 "Margin" user)
    (46 "B.CrtYd" user "B.Courtyard")
    (47 "F.CrtYd" user "F.Courtyard")
    (48 "B.Fab" user)
    (49 "F.Fab" user)
  )
	(footprint "antmicro-footprints:NetTie-2_SMD_Pad0.127mm" (layer "B.Cu")
    (at 116.16 86.95 135)
    (descr "Net tie, 2 pin, 0.127mm  SMD pads")
    (tags "net tie")
    (property "Author" "Antmicro")
    (property "License" "Apache-2.0")
    (property "MPN" "")
    (property "Manufacturer" "")
    (property "Sheetfile" "power.kicad_sch")
    (property "Sheetname" "Power")
    (property "exclude_from_bom" "")
    (property "ki_description" "Net tie, 2 pins")
    (attr through_hole exclude_from_pos_files exclude_from_bom)
    (net_tie_pad_groups "1, 2")
    (fp_text reference "TP11" (at -0.128 1.345 135) (layer "B.SilkS") hide
        (effects (font (size 0.7 0.7) (thickness 0.15)) (justify right bottom mirror))
    )
    (fp_text value "Net-Tie_P0.127mm" (at 0 -1.199 135) (layer "B.Fab")
        (effects (font (size 0.7 0.7) (thickness 0.15)) (justify right bottom mirror))
    )
    (fp_text user "License: Apache-2.0" (at -0.128 -5.6 135) (layer "B.Fab") hide
        (effects (font (size 0.7 0.7) (thickness 0.15)) (justify right bottom mirror))
    )
    (fp_text user "${REFERENCE}" (at -0.128 -3.2 135) (layer "B.Fab") hide
        (effects (font (size 0.7 0.7) (thickness 0.15)) (justify right bottom mirror))
    )
    (fp_text user "Author: Antmicro" (at -0.128 -4.4 135) (layer "B.Fab") hide
        (effects (font (size 0.7 0.7) (thickness 0.15)) (justify right bottom mirror))
    )
    (fp_poly
      (pts
        (xy -0.0635 0.0635)
        (xy 0.0625 0.0635)
        (xy 0.0625 -0.0635)
        (xy -0.0635 -0.0635)
      )

      (stroke (width 0) (type solid)) (fill solid) (layer "B.Cu"))
    (fp_poly
      (pts
        (xy 0.2 0.16)
        (xy 0.29 0.07)
        (xy 0.29 -0.07)
        (xy 0.2 -0.16)
        (xy -0.2 -0.16)
        (xy -0.29 -0.07)
        (xy -0.29 0.06)
        (xy -0.19 0.16)
      )

      (stroke (width 0.05) (type solid)) (fill none) (layer "B.CrtYd"))
    (pad "1" smd roundrect (at -0.127 0 315) (size 0.127 0.127) (layers "B.Cu") (roundrect_rratio 0.5)
      (chamfer_ratio 0) (chamfer top_left bottom_left)
      (net 60 "12V0_DCDC") (pinfunction "1") (pintype "passive"))
    (pad "2" smd roundrect (at 0.126 0 135) (size 0.127 0.127) (layers "B.Cu") (roundrect_rratio 0.5)
      (chamfer_ratio 0) (chamfer top_left bottom_left)
      (net 85 "/Power/I_SENSE_N") (pinfunction "2") (pintype "passive"))
  )
	(footprint "antmicro-footprints:R_0402_1005Metric" (layer "B.Cu")
    (at 145.62 75.96 180)
    (descr "Resistor SMD 0402")
    (tags "resistor SMD 0402")
    (property "Author" "Antmicro")
    (property "License" "Apache-2.0")
    (property "MPN" "CR0402-FX-1004GLF")
    (property "Manufacturer" "Bourns")
    (property "Sheetfile" "tb.kicad_sch")
    (property "Sheetname" "TB Controller")
    (property "Tolerance" "1%")
    (property "Val" "1M")
    (property "ki_description" "SMD Chip Resistor, 1 Mohm, ± 1%, 62.5 mW, 0402 [1005 Metric], Thick Film, General Purpose")
    (property "ki_keywords" "0402, SMT, RESISTOR, PASSIVE")
    (attr smd)
    (fp_text reference "R71" (at -3.097 -0.367) (layer "B.SilkS")
        (effects (font (size 0.7 0.7) (thickness 0.15)) (justify left bottom mirror))
    )
    (fp_text value "R_1M_0402" (at -1.011843 -1.772047) (layer "B.Fab")
        (effects (font (size 0.7 0.7) (thickness 0.15)) (justify left bottom mirror))
    )
    (fp_text user "License: Apache-2.0" (at -0.95 -5.169) (layer "B.Fab") hide
        (effects (font (size 0.7 0.7) (thickness 0.15)) (justify left bottom mirror))
    )
    (fp_text user "Author: Antmicro" (at -0.95 -4.169) (layer "B.Fab") hide
        (effects (font (size 0.7 0.7) (thickness 0.15)) (justify left bottom mirror))
    )
    (fp_text user "${REFERENCE}" (at -0.95 -3.168) (layer "B.Fab") hide
        (effects (font (size 0.7 0.7) (thickness 0.15)) (justify left bottom mirror))
    )
    (fp_rect (start -0.925 0.47) (end 0.925 -0.47)
      (stroke (width 0.05) (type default)) (fill none) (layer "B.CrtYd"))
    (fp_rect (start -0.5 0.25) (end 0.5 -0.25)
      (stroke (width 0.15) (type solid)) (fill none) (layer "B.Fab"))
    (pad "1" smd roundrect (at -0.48 0 180) (size 0.59 0.64) (layers "B.Cu" "B.Paste" "B.Mask") (roundrect_rratio 0.25)
      (net 186 "Net-(U4E-PB_LSRX)") (pintype "passive"))
    (pad "2" smd roundrect (at 0.48 0 180) (size 0.59 0.64) (layers "B.Cu" "B.Paste" "B.Mask") (roundrect_rratio 0.25)
      (net 1 "GND") (pintype "passive"))
  )
	(footprint "antmicro-footprints:R_0402_1005Metric" (layer "B.Cu")
    (at 103.69 88.425 -90)
    (descr "Resistor SMD 0402")
    (tags "resistor SMD 0402")
    (property "Author" "Antmicro")
    (property "License" "Apache-2.0")
    (property "MPN" "CR0402-FX-1002GLF")
    (property "Manufacturer" "Bourns")
    (property "Sheetfile" "power.kicad_sch")
    (property "Sheetname" "Power")
    (property "Tolerance" "1%")
    (property "Val" "10k")
    (property "ki_description" "SMD Chip Resistor, 10 kohm, ± 1%, 62.5 mW, 0402 [1005 Metric], Thick Film, General Purpose")
    (property "ki_keywords" "0402, SMT, RESISTOR, PASSIVE")
    (attr smd)
    (fp_text reference "R91" (at -3.081 -0.45 90) (layer "B.SilkS")
        (effects (font (size 0.7 0.7) (thickness 0.15)) (justify left bottom mirror))
    )
    (fp_text value "R_10k_0402" (at -1.011843 -1.772047 90) (layer "B.Fab")
        (effects (font (size 0.7 0.7) (thickness 0.15)) (justify left bottom mirror))
    )
    (fp_text user "${REFERENCE}" (at -0.95 -3.168 90) (layer "B.Fab") hide
        (effects (font (size 0.7 0.7) (thickness 0.15)) (justify left bottom mirror))
    )
    (fp_text user "License: Apache-2.0" (at -0.95 -5.169 90) (layer "B.Fab") hide
        (effects (font (size 0.7 0.7) (thickness 0.15)) (justify left bottom mirror))
    )
    (fp_text user "Author: Antmicro" (at -0.95 -4.169 90) (layer "B.Fab") hide
        (effects (font (size 0.7 0.7) (thickness 0.15)) (justify left bottom mirror))
    )
    (fp_rect (start -0.925 0.47) (end 0.925 -0.47)
      (stroke (width 0.05) (type default)) (fill none) (layer "B.CrtYd"))
    (fp_rect (start -0.5 0.25) (end 0.5 -0.25)
      (stroke (width 0.15) (type solid)) (fill none) (layer "B.Fab"))
    (pad "1" smd roundrect (at -0.48 0 270) (size 0.59 0.64) (layers "B.Cu" "B.Paste" "B.Mask") (roundrect_rratio 0.25)
      (net 61 "12V0_MOLEX") (pintype "passive"))
    (pad "2" smd roundrect (at 0.48 0 270) (size 0.59 0.64) (layers "B.Cu" "B.Paste" "B.Mask") (roundrect_rratio 0.25)
      (net 140 "Net-(Q2-B)") (pintype "passive"))
  )
	(footprint "antmicro-footprints:C_0402_1005Metric" (layer "B.Cu")
    (at 132.85 79.85 180)
    (descr "Capacitor SMD 0402")
    (tags "capacitor SMD 0402")
    (property "Author" "Antmicro")
    (property "Dielectric" "")
    (property "License" "Apache-2.0")
    (property "MPN" "C1005X6S1A105K050BC")
    (property "Manufacturer" "TDK")
    (property "Sheetfile" "tb-power.kicad_sch")
    (property "Sheetname" "Thunderbolt Controller - Power")
    (property "Val" "1u")
    (property "Voltage" "")
    (property "ki_description" "SMD Multilayer Ceramic Capacitor, 1 µF, 10 V, 0402 [1005 Metric], ± 10%, X6S, C")
    (property "ki_keywords" "0402, SMT, CAPACITOR, PASSIVE, CERAMIC, MLCC")
    (attr smd)
    (fp_text reference "C53" (at -17.518 -7.653) (layer "B.SilkS")
        (effects (font (size 0.7 0.7) (thickness 0.15)) (justify left bottom mirror))
    )
    (fp_text value "C_1u_0402" (at -1.022927 -2.155213) (layer "B.Fab")
        (effects (font (size 0.7 0.7) (thickness 0.15)) (justify left bottom mirror))
    )
    (fp_text user "${REFERENCE}" (at -0.939 -4.599) (layer "B.Fab") hide
        (effects (font (size 0.7 0.7) (thickness 0.15)) (justify left bottom mirror))
    )
    (fp_text user "License: Apache-2.0" (at -0.939 -5.799) (layer "B.Fab") hide
        (effects (font (size 0.7 0.7) (thickness 0.15)) (justify left bottom mirror))
    )
    (fp_text user "Author: Antmicro" (at -0.939 -3.399) (layer "B.Fab") hide
        (effects (font (size 0.7 0.7) (thickness 0.15)) (justify left bottom mirror))
    )
    (fp_rect (start -0.925 0.47) (end 0.925 -0.47)
      (stroke (width 0.05) (type default)) (fill none) (layer "B.CrtYd"))
    (fp_line (start -0.494 -0.248) (end -0.494 0.25)
      (stroke (width 0.15) (type solid)) (layer "B.Fab"))
    (fp_line (start -0.494 0.25) (end 0.504 0.25)
      (stroke (width 0.15) (type solid)) (layer "B.Fab"))
    (fp_line (start 0.504 -0.248) (end -0.494 -0.248)
      (stroke (width 0.15) (type solid)) (layer "B.Fab"))
    (fp_line (start 0.504 0.25) (end 0.504 -0.248)
      (stroke (width 0.15) (type solid)) (layer "B.Fab"))
    (pad "1" smd roundrect (at -0.48 0 180) (size 0.59 0.64) (layers "B.Cu" "B.Paste" "B.Mask") (roundrect_rratio 0.25)
      (net 1 "GND") (pintype "passive"))
    (pad "2" smd roundrect (at 0.48 0 180) (size 0.59 0.64) (layers "B.Cu" "B.Paste" "B.Mask") (roundrect_rratio 0.25)
      (net 106 "Net-(C53-Pad2)") (pintype "passive"))
  )
	(footprint "antmicro-footprints:C_0402_1005Metric" (layer "B.Cu")
    (at 159.91 59.47 -90)
    (descr "Capacitor SMD 0402")
    (tags "capacitor SMD 0402")
    (property "Author" "Antmicro")
    (property "Dielectric" "X5S")
    (property "License" "Apache-2.0")
    (property "MPN" "GRM155C61E475ME15J")
    (property "Manufacturer" "Murata")
    (property "Sheetfile" "power.kicad_sch")
    (property "Sheetname" "Power")
    (property "Val" "4u7")
    (property "Voltage" "25V")
    (property "dnp" "")
    (property "ki_description" "SMD Multilayer Ceramic Capacitor")
    (property "ki_keywords" "0402, SMT, CAPACITOR, PASSIVE, CERAMIC")
    (attr smd)
    (fp_text reference "C21" (at -3.082 -0.364 90) (layer "B.SilkS")
        (effects (font (size 0.7 0.7) (thickness 0.15)) (justify left bottom mirror))
    )
    (fp_text value "C_4u7_25V_0402" (at -1.022927 -2.155213 90) (layer "B.Fab")
        (effects (font (size 0.7 0.7) (thickness 0.15)) (justify left bottom mirror))
    )
    (fp_text user "License: Apache-2.0" (at -0.939 -5.799 90) (layer "B.Fab") hide
        (effects (font (size 0.7 0.7) (thickness 0.15)) (justify left bottom mirror))
    )
    (fp_text user "${REFERENCE}" (at -0.939 -4.599 90) (layer "B.Fab") hide
        (effects (font (size 0.7 0.7) (thickness 0.15)) (justify left bottom mirror))
    )
    (fp_text user "Author: Antmicro" (at -0.939 -3.399 90) (layer "B.Fab") hide
        (effects (font (size 0.7 0.7) (thickness 0.15)) (justify left bottom mirror))
    )
    (fp_rect (start -0.925 0.47) (end 0.925 -0.47)
      (stroke (width 0.05) (type default)) (fill none) (layer "B.CrtYd"))
    (fp_line (start -0.494 -0.248) (end -0.494 0.25)
      (stroke (width 0.15) (type solid)) (layer "B.Fab"))
    (fp_line (start -0.494 0.25) (end 0.504 0.25)
      (stroke (width 0.15) (type solid)) (layer "B.Fab"))
    (fp_line (start 0.504 -0.248) (end -0.494 -0.248)
      (stroke (width 0.15) (type solid)) (layer "B.Fab"))
    (fp_line (start 0.504 0.25) (end 0.504 -0.248)
      (stroke (width 0.15) (type solid)) (layer "B.Fab"))
    (pad "1" smd roundrect (at -0.48 0 270) (size 0.59 0.64) (layers "B.Cu" "B.Paste" "B.Mask") (roundrect_rratio 0.25)
      (net 1 "GND") (pintype "passive"))
    (pad "2" smd roundrect (at 0.48 0 270) (size 0.59 0.64) (layers "B.Cu" "B.Paste" "B.Mask") (roundrect_rratio 0.25)
      (net 20 "PP_5V0") (pintype "passive"))
  )
	(footprint "antmicro-footprints:R_0402_1005Metric" (layer "B.Cu")
    (at 141.15 78.39 -90)
    (descr "Resistor SMD 0402")
    (tags "resistor SMD 0402")
    (property "Author" "Antmicro")
    (property "License" "Apache-2.0")
    (property "MPN" "CR0402-FX-4990GLF")
    (property "Manufacturer" "Bourns")
    (property "Sheetfile" "tb.kicad_sch")
    (property "Sheetname" "TB Controller")
    (property "Tolerance" "1%")
    (property "Val" "499R")
    (property "ki_description" "SMD Chip Resistor, 499 ohm, ± 1%, 63 mW, 0402 [1005 Metric], Thick Film, General Purpose")
    (property "ki_keywords" "0402, SMT, RESISTOR, PASSIVE")
    (attr smd)
    (fp_text reference "R68" (at 0.985 -0.455 90) (layer "B.SilkS")
        (effects (font (size 0.7 0.7) (thickness 0.15)) (justify left bottom mirror))
    )
    (fp_text value "R_499R_0402" (at -1.011843 -1.772047 90) (layer "B.Fab")
        (effects (font (size 0.7 0.7) (thickness 0.15)) (justify left bottom mirror))
    )
    (fp_text user "Author: Antmicro" (at -0.95 -4.169 90) (layer "B.Fab") hide
        (effects (font (size 0.7 0.7) (thickness 0.15)) (justify left bottom mirror))
    )
    (fp_text user "License: Apache-2.0" (at -0.95 -5.169 90) (layer "B.Fab") hide
        (effects (font (size 0.7 0.7) (thickness 0.15)) (justify left bottom mirror))
    )
    (fp_text user "${REFERENCE}" (at -0.95 -3.168 90) (layer "B.Fab") hide
        (effects (font (size 0.7 0.7) (thickness 0.15)) (justify left bottom mirror))
    )
    (fp_rect (start -0.925 0.47) (end 0.925 -0.47)
      (stroke (width 0.05) (type default)) (fill none) (layer "B.CrtYd"))
    (fp_rect (start -0.5 0.25) (end 0.5 -0.25)
      (stroke (width 0.15) (type solid)) (fill none) (layer "B.Fab"))
    (pad "1" smd roundrect (at -0.48 0 270) (size 0.59 0.64) (layers "B.Cu" "B.Paste" "B.Mask") (roundrect_rratio 0.25)
      (net 1 "GND") (pintype "passive"))
    (pad "2" smd roundrect (at 0.48 0 270) (size 0.59 0.64) (layers "B.Cu" "B.Paste" "B.Mask") (roundrect_rratio 0.25)
      (net 182 "Net-(U4E-PA_USB2_RBIAS)") (pintype "passive"))
  )
	(footprint "antmicro-footprints:R_0402_1005Metric" (layer "B.Cu")
    (at 133.125 66.82 -90)
    (descr "Resistor SMD 0402")
    (tags "resistor SMD 0402")
    (property "Author" "Antmicro")
    (property "License" "Apache-2.0")
    (property "MPN" "CR0402-FX-2201GLF")
    (property "Manufacturer" "Bourns")
    (property "Sheetfile" "tb.kicad_sch")
    (property "Sheetname" "TB Controller")
    (property "Tolerance" "1%")
    (property "Val" "2k2")
    (property "ki_description" "SMD Chip Resistor, 2.2 kohm, ± 1%, 62.5 mW, 0402 [1005 Metric], Thick Film, General Purpose")
    (property "ki_keywords" "0402, SMT, RESISTOR, PASSIVE")
    (attr smd)
    (fp_text reference "R61" (at -3.066 -0.325 90) (layer "B.SilkS")
        (effects (font (size 0.7 0.7) (thickness 0.15)) (justify left bottom mirror))
    )
    (fp_text value "R_2k2_0402" (at -1.011843 -1.772047 90) (layer "B.Fab")
        (effects (font (size 0.7 0.7) (thickness 0.15)) (justify left bottom mirror))
    )
    (fp_text user "${REFERENCE}" (at -0.95 -3.168 90) (layer "B.Fab") hide
        (effects (font (size 0.7 0.7) (thickness 0.15)) (justify left bottom mirror))
    )
    (fp_text user "License: Apache-2.0" (at -0.95 -5.169 90) (layer "B.Fab") hide
        (effects (font (size 0.7 0.7) (thickness 0.15)) (justify left bottom mirror))
    )
    (fp_text user "Author: Antmicro" (at -0.95 -4.169 90) (layer "B.Fab") hide
        (effects (font (size 0.7 0.7) (thickness 0.15)) (justify left bottom mirror))
    )
    (fp_rect (start -0.925 0.47) (end 0.925 -0.47)
      (stroke (width 0.05) (type default)) (fill none) (layer "B.CrtYd"))
    (fp_rect (start -0.5 0.25) (end 0.5 -0.25)
      (stroke (width 0.15) (type solid)) (fill none) (layer "B.Fab"))
    (pad "1" smd roundrect (at -0.48 0 270) (size 0.59 0.64) (layers "B.Cu" "B.Paste" "B.Mask") (roundrect_rratio 0.25)
      (net 1 "GND") (pintype "passive"))
    (pad "2" smd roundrect (at 0.48 0 270) (size 0.59 0.64) (layers "B.Cu" "B.Paste" "B.Mask") (roundrect_rratio 0.25)
      (net 175 "Net-(U4C-DPSNK1_DDC_CLK)") (pintype "passive"))
  )
	(footprint "antmicro-footprints:C_0402_1005Metric" (layer "B.Cu")
    (at 153.41 61.97 180)
    (descr "Capacitor SMD 0402")
    (tags "capacitor SMD 0402")
    (property "Author" "Antmicro")
    (property "Dielectric" "")
    (property "License" "Apache-2.0")
    (property "MPN" "C1005X5R1A225K050BC")
    (property "Manufacturer" "TDK")
    (property "Sheetfile" "power.kicad_sch")
    (property "Sheetname" "Power")
    (property "Val" "2u2")
    (property "Voltage" "")
    (property "ki_description" "SMD Multilayer Ceramic Capacitor, 2.2 µF, 10 V, 0402 [1005 Metric], ± 10%, X5R, C")
    (property "ki_keywords" "0402, SMT, CAPACITOR, PASSIVE, CERAMIC, MLCC")
    (attr smd)
    (fp_text reference "C37" (at -0.768 -4.451) (layer "B.SilkS")
        (effects (font (size 0.7 0.7) (thickness 0.15)) (justify left bottom mirror))
    )
    (fp_text value "C_2u2_0402" (at -1.022927 -2.155213) (layer "B.Fab")
        (effects (font (size 0.7 0.7) (thickness 0.15)) (justify left bottom mirror))
    )
    (fp_text user "License: Apache-2.0" (at -0.939 -5.799) (layer "B.Fab") hide
        (effects (font (size 0.7 0.7) (thickness 0.15)) (justify left bottom mirror))
    )
    (fp_text user "Author: Antmicro" (at -0.939 -3.399) (layer "B.Fab") hide
        (effects (font (size 0.7 0.7) (thickness 0.15)) (justify left bottom mirror))
    )
    (fp_text user "${REFERENCE}" (at -0.939 -4.599) (layer "B.Fab") hide
        (effects (font (size 0.7 0.7) (thickness 0.15)) (justify left bottom mirror))
    )
    (fp_rect (start -0.925 0.47) (end 0.925 -0.47)
      (stroke (width 0.05) (type default)) (fill none) (layer "B.CrtYd"))
    (fp_line (start -0.494 -0.248) (end -0.494 0.25)
      (stroke (width 0.15) (type solid)) (layer "B.Fab"))
    (fp_line (start -0.494 0.25) (end 0.504 0.25)
      (stroke (width 0.15) (type solid)) (layer "B.Fab"))
    (fp_line (start 0.504 -0.248) (end -0.494 -0.248)
      (stroke (width 0.15) (type solid)) (layer "B.Fab"))
    (fp_line (start 0.504 0.25) (end 0.504 -0.248)
      (stroke (width 0.15) (type solid)) (layer "B.Fab"))
    (pad "1" smd roundrect (at -0.48 0 180) (size 0.59 0.64) (layers "B.Cu" "B.Paste" "B.Mask") (roundrect_rratio 0.25)
      (net 104 "Net-(U3-LDO_BMC)") (pintype "passive"))
    (pad "2" smd roundrect (at 0.48 0 180) (size 0.59 0.64) (layers "B.Cu" "B.Paste" "B.Mask") (roundrect_rratio 0.25)
      (net 1 "GND") (pintype "passive"))
  )
	(footprint "antmicro-footprints:R_0402_1005Metric" (layer "B.Cu")
    (at 151.41 59.97)
    (descr "Resistor SMD 0402")
    (tags "resistor SMD 0402")
    (property "Author" "Antmicro")
    (property "License" "Apache-2.0")
    (property "MPN" "CR0402-FX-1002GLF")
    (property "Manufacturer" "Bourns")
    (property "Sheetfile" "power.kicad_sch")
    (property "Sheetname" "Power")
    (property "Tolerance" "1%")
    (property "Val" "10k")
    (property "ki_description" "SMD Chip Resistor, 10 kohm, ± 1%, 62.5 mW, 0402 [1005 Metric], Thick Film, General Purpose")
    (property "ki_keywords" "0402, SMT, RESISTOR, PASSIVE")
    (attr smd)
    (fp_text reference "R2" (at -0.915 0.482 180) (layer "B.SilkS")
        (effects (font (size 0.7 0.7) (thickness 0.15)) (justify left bottom mirror))
    )
    (fp_text value "R_10k_0402" (at -1.011843 -1.772047 180) (layer "B.Fab")
        (effects (font (size 0.7 0.7) (thickness 0.15)) (justify left bottom mirror))
    )
    (fp_text user "${REFERENCE}" (at -0.95 -3.168 180) (layer "B.Fab") hide
        (effects (font (size 0.7 0.7) (thickness 0.15)) (justify left bottom mirror))
    )
    (fp_text user "Author: Antmicro" (at -0.95 -4.169 180) (layer "B.Fab") hide
        (effects (font (size 0.7 0.7) (thickness 0.15)) (justify left bottom mirror))
    )
    (fp_text user "License: Apache-2.0" (at -0.95 -5.169 180) (layer "B.Fab") hide
        (effects (font (size 0.7 0.7) (thickness 0.15)) (justify left bottom mirror))
    )
    (fp_rect (start -0.925 0.47) (end 0.925 -0.47)
      (stroke (width 0.05) (type default)) (fill none) (layer "B.CrtYd"))
    (fp_rect (start -0.5 0.25) (end 0.5 -0.25)
      (stroke (width 0.15) (type solid)) (fill none) (layer "B.Fab"))
    (pad "1" smd roundrect (at -0.48 0) (size 0.59 0.64) (layers "B.Cu" "B.Paste" "B.Mask") (roundrect_rratio 0.25)
      (net 56 "I2C1_IRQ") (pintype "passive"))
    (pad "2" smd roundrect (at 0.48 0) (size 0.59 0.64) (layers "B.Cu" "B.Paste" "B.Mask") (roundrect_rratio 0.25)
      (net 2 "3V3_SYS") (pintype "passive"))
  )
)
